(kicad_pcb
	(version 20260206)
	(generator "pcbnew")
	(generator_version "10.0")
	(general
		(thickness 1.6)
		(legacy_teardrops no)
	)
	(paper "A4")
	(title_block
		(title "v1-chassis-manager — T6M_CM_d_v01_1031_1645.brd")
		(comment 1 "Open CloudServer (Microsoft) / footprints 1806-1815 of 2512")
	)
	(layers
		(0 "F.Cu" signal "TOP")
		(4 "In1.Cu" signal "GND1")
		(6 "In2.Cu" signal "IN1")
		(8 "In3.Cu" signal "VCC1")
		(10 "In4.Cu" signal "VCC2")
		(12 "In5.Cu" signal "GND2")
		(14 "In6.Cu" signal "IN2")
		(16 "In7.Cu" signal "IN3")
		(18 "In8.Cu" signal "GND3")
		(2 "B.Cu" signal "BOTTOM")
		(9 "F.Adhes" user "F.Adhesive")
		(11 "B.Adhes" user "B.Adhesive")
		(13 "F.Paste" user "Package Geometry/Pastemask Top")
		(15 "B.Paste" user "Package Geometry/Pastemask Bottom")
		(5 "F.SilkS" user "Ref Des/Silkscreen Top")
		(7 "B.SilkS" user "Ref Des/Silkscreen Bottom")
		(1 "F.Mask" user "Board Geometry/Soldermask Top")
		(3 "B.Mask" user "Board Geometry/Soldermask Bottom")
		(17 "Dwgs.User" user "User.Drawings")
		(19 "Cmts.User" user "User.Comments")
		(21 "Eco1.User" user "User.Eco1")
		(23 "Eco2.User" user "User.Eco2")
		(25 "Edge.Cuts" user "Board Geometry/Outline")
		(27 "Margin" user)
		(31 "F.CrtYd" user "Package Geometry/Place Bound Top")
		(29 "B.CrtYd" user "Package Geometry/Place Bound Bottom")
		(35 "F.Fab" user "Ref Des/Assembly Top")
		(33 "B.Fab" user "Ref Des/Assembly Bottom")
	)
	(footprint ""
		(layer "B.Cu")
		(at 64.074294 -68.76034 90)
		(property "Reference" "L10"
			(at -33.95345 -14.250924 270)
			(unlocked yes)
			(layer "B.SilkS")
			(effects
				(font
					(size 0.7874 0.5842)
					(thickness 0.1524)
				)
				(justify left mirror)
			)
		)
		(property "Value" ""
			(at 0 0 90)
			(layer "B.Fab")
			(effects
				(font
					(size 1.27 1.27)
				)
				(justify mirror)
			)
		)
		(duplicate_pad_numbers_are_jumpers no)
		(fp_line
			(start 0.7874 -0.4064)
			(end -0.7874 -0.4064)
			(stroke
				(width 0.1524)
				(type default)
			)
			(layer "B.SilkS")
		)
		(fp_line
			(start -0.7874 -0.4064)
			(end -0.7874 0.4064)
			(stroke
				(width 0.1524)
				(type default)
			)
			(layer "B.SilkS")
		)
		(fp_line
			(start 0.7874 0.4064)
			(end 0.7874 -0.4064)
			(stroke
				(width 0.1524)
				(type default)
			)
			(layer "B.SilkS")
		)
		(fp_line
			(start 0.0889 0.4064)
			(end 0.0889 -0.4064)
			(stroke
				(width 0.1524)
				(type default)
			)
			(layer "B.SilkS")
		)
		(fp_line
			(start -0.0889 0.4064)
			(end -0.0889 -0.4064)
			(stroke
				(width 0.1524)
				(type default)
			)
			(layer "B.SilkS")
		)
		(fp_line
			(start -0.7874 0.4064)
			(end 0.7874 0.4064)
			(stroke
				(width 0.1524)
				(type default)
			)
			(layer "B.SilkS")
		)
		(fp_poly
			(pts
				(xy 0.5334 0.254) (xy 0.635 0.254) (xy 0.635 0.2286) (xy 0.635 -0.254) (xy 0.5334 -0.254) (xy 0.5334 -0.2794)
				(xy -0.5334 -0.2794) (xy -0.5334 -0.254) (xy -0.635 -0.254) (xy -0.635 0.254) (xy -0.5334 0.254)
				(xy -0.5334 0.2794) (xy 0.508 0.2794) (xy 0.5334 0.2794)
			)
			(stroke
				(width 0)
				(type default)
			)
			(fill no)
			(layer "B.CrtYd")
		)
		(pad "1" smd rect
			(at -0.40005 0 270)
			(size 0.4572 0.508)
			(layers "B.Cu" "B.Mask" "B.Paste")
			(net "PV_VDDR_NODE1")
		)
		(pad "2" smd rect
			(at 0.40005 0 270)
			(size 0.4572 0.508)
			(layers "B.Cu" "B.Mask" "B.Paste")
			(net "PV_VDDR_VCCCLK_DDR3_NODE1")
		)
	)
	(footprint ""
		(layer "B.Cu")
		(at 128.762252 -136.74471 90)
		(property "Reference" "C193"
			(at -5.94741 0.25781 270)
			(unlocked yes)
			(layer "B.SilkS")
			(effects
				(font
					(size 0.7874 0.5842)
					(thickness 0.1524)
				)
				(justify left mirror)
			)
		)
		(property "Value" ""
			(at 0 0 90)
			(layer "B.Fab")
			(effects
				(font
					(size 1.27 1.27)
				)
				(justify mirror)
			)
		)
		(duplicate_pad_numbers_are_jumpers no)
		(fp_line
			(start 0.7874 -0.4064)
			(end -0.7874 -0.4064)
			(stroke
				(width 0.1524)
				(type default)
			)
			(layer "B.SilkS")
		)
		(fp_line
			(start -0.7874 -0.4064)
			(end -0.7874 0.4064)
			(stroke
				(width 0.1524)
				(type default)
			)
			(layer "B.SilkS")
		)
		(fp_line
			(start 0 0.381)
			(end 0 -0.381)
			(stroke
				(width 0.1524)
				(type default)
			)
			(layer "B.SilkS")
		)
		(fp_line
			(start 0.7874 0.4064)
			(end 0.7874 -0.4064)
			(stroke
				(width 0.1524)
				(type default)
			)
			(layer "B.SilkS")
		)
		(fp_line
			(start -0.7874 0.4064)
			(end 0.7874 0.4064)
			(stroke
				(width 0.1524)
				(type default)
			)
			(layer "B.SilkS")
		)
		(fp_poly
			(pts
				(xy 0.5334 0.254) (xy 0.635 0.254) (xy 0.635 0.2286) (xy 0.635 -0.254) (xy 0.5334 -0.254) (xy 0.5334 -0.2794)
				(xy -0.5334 -0.2794) (xy -0.5334 -0.254) (xy -0.635 -0.254) (xy -0.635 0.254) (xy -0.5334 0.254)
				(xy -0.5334 0.2794) (xy 0.508 0.2794) (xy 0.5334 0.2794)
			)
			(stroke
				(width 0)
				(type default)
			)
			(fill no)
			(layer "B.CrtYd")
		)
		(pad "1" smd rect
			(at -0.40005 0 270)
			(size 0.4572 0.508)
			(layers "B.Cu" "B.Mask" "B.Paste")
			(net "CLK_100M_PCIE_SW_NODE1_DN")
		)
		(pad "2" smd rect
			(at 0.40005 0 270)
			(size 0.4572 0.508)
			(layers "B.Cu" "B.Mask" "B.Paste")
			(net "CLK_100M_PCIE_SW_NODE1_C_DN")
		)
	)
	(footprint ""
		(layer "B.Cu")
		(at 64.0715 -79.166466 -90)
		(property "Reference" "C81"
			(at 32.190436 14.44625 270)
			(unlocked yes)
			(layer "B.SilkS")
			(effects
				(font
					(size 0.7874 0.5842)
					(thickness 0.1524)
				)
				(justify left mirror)
			)
		)
		(property "Value" ""
			(at 0 0 90)
			(layer "B.Fab")
			(effects
				(font
					(size 1.27 1.27)
				)
				(justify mirror)
			)
		)
		(duplicate_pad_numbers_are_jumpers no)
		(fp_line
			(start -0.7874 0.4064)
			(end 0.7874 0.4064)
			(stroke
				(width 0.1524)
				(type default)
			)
			(layer "B.SilkS")
		)
		(fp_line
			(start 0.7874 0.4064)
			(end 0.7874 -0.4064)
			(stroke
				(width 0.1524)
				(type default)
			)
			(layer "B.SilkS")
		)
		(fp_line
			(start 0 0.381)
			(end 0 -0.381)
			(stroke
				(width 0.1524)
				(type default)
			)
			(layer "B.SilkS")
		)
		(fp_line
			(start -0.7874 -0.4064)
			(end -0.7874 0.4064)
			(stroke
				(width 0.1524)
				(type default)
			)
			(layer "B.SilkS")
		)
		(fp_line
			(start 0.7874 -0.4064)
			(end -0.7874 -0.4064)
			(stroke
				(width 0.1524)
				(type default)
			)
			(layer "B.SilkS")
		)
		(fp_poly
			(pts
				(xy 0.5334 0.254) (xy 0.635 0.254) (xy 0.635 0.2286) (xy 0.635 -0.254) (xy 0.5334 -0.254) (xy 0.5334 -0.2794)
				(xy -0.5334 -0.2794) (xy -0.5334 -0.254) (xy -0.635 -0.254) (xy -0.635 0.254) (xy -0.5334 0.254)
				(xy -0.5334 0.2794) (xy 0.508 0.2794) (xy 0.5334 0.2794)
			)
			(stroke
				(width 0)
				(type default)
			)
			(fill no)
			(layer "B.CrtYd")
		)
		(pad "1" smd rect
			(at -0.40005 0 90)
			(size 0.4572 0.508)
			(layers "B.Cu" "B.Mask" "B.Paste")
			(net "PV_VCCP_NODE1")
		)
		(pad "2" smd rect
			(at 0.40005 0 90)
			(size 0.4572 0.508)
			(layers "B.Cu" "B.Mask" "B.Paste")
			(net "GND")
		)
	)
	(footprint ""
		(layer "B.Cu")
		(at 56.054498 -96.696784 90)
		(property "Reference" "R54"
			(at 6.405118 -4.364228 270)
			(unlocked yes)
			(layer "B.SilkS")
			(effects
				(font
					(size 0.7874 0.5842)
					(thickness 0.1524)
				)
				(justify left mirror)
			)
		)
		(property "Value" ""
			(at 0 0 90)
			(layer "B.Fab")
			(effects
				(font
					(size 1.27 1.27)
				)
				(justify mirror)
			)
		)
		(duplicate_pad_numbers_are_jumpers no)
		(fp_line
			(start 0.7874 -0.4064)
			(end -0.7874 -0.4064)
			(stroke
				(width 0.1524)
				(type default)
			)
			(layer "B.SilkS")
		)
		(fp_line
			(start -0.7874 -0.4064)
			(end -0.7874 0.4064)
			(stroke
				(width 0.1524)
				(type default)
			)
			(layer "B.SilkS")
		)
		(fp_line
			(start 0.7874 0.4064)
			(end 0.7874 -0.4064)
			(stroke
				(width 0.1524)
				(type default)
			)
			(layer "B.SilkS")
		)
		(fp_line
			(start -0.7874 0.4064)
			(end 0.7874 0.4064)
			(stroke
				(width 0.1524)
				(type default)
			)
			(layer "B.SilkS")
		)
		(fp_poly
			(pts
				(xy 0.508 0.2794) (xy 0.508 0.2286) (xy 0.635 0.2286) (xy 0.635 -0.254) (xy 0.5334 -0.254) (xy 0.5334 -0.2794)
				(xy -0.5334 -0.2794) (xy -0.5334 -0.254) (xy -0.635 -0.254) (xy -0.635 0.254) (xy -0.5334 0.254)
				(xy -0.5334 0.2794)
			)
			(stroke
				(width 0)
				(type default)
			)
			(fill no)
			(layer "B.CrtYd")
		)
		(pad "1" smd rect
			(at -0.40005 0 270)
			(size 0.4572 0.508)
			(layers "B.Cu" "B.Mask" "B.Paste")
			(net "PD_CPU_NODE1_DFX_GPIO_GRP1_2")
		)
		(pad "2" smd rect
			(at 0.40005 0 270)
			(size 0.4572 0.508)
			(layers "B.Cu" "B.Mask" "B.Paste")
			(net "GND")
		)
	)
	(footprint ""
		(layer "B.Cu")
		(at 64.782192 -131.551426 90)
		(property "Reference" "C253"
			(at -54.864 -41.316402 270)
			(unlocked yes)
			(layer "B.SilkS")
			(effects
				(font
					(size 0.7874 0.5842)
					(thickness 0.1524)
				)
				(justify left mirror)
			)
		)
		(property "Value" ""
			(at 0 0 90)
			(layer "B.Fab")
			(effects
				(font
					(size 1.27 1.27)
				)
				(justify mirror)
			)
		)
		(duplicate_pad_numbers_are_jumpers no)
		(fp_line
			(start 0.7874 -0.4064)
			(end -0.7874 -0.4064)
			(stroke
				(width 0.1524)
				(type default)
			)
			(layer "B.SilkS")
		)
		(fp_line
			(start -0.7874 -0.4064)
			(end -0.7874 0.4064)
			(stroke
				(width 0.1524)
				(type default)
			)
			(layer "B.SilkS")
		)
		(fp_line
			(start 0 0.381)
			(end 0 -0.381)
			(stroke
				(width 0.1524)
				(type default)
			)
			(layer "B.SilkS")
		)
		(fp_line
			(start 0.7874 0.4064)
			(end 0.7874 -0.4064)
			(stroke
				(width 0.1524)
				(type default)
			)
			(layer "B.SilkS")
		)
		(fp_line
			(start -0.7874 0.4064)
			(end 0.7874 0.4064)
			(stroke
				(width 0.1524)
				(type default)
			)
			(layer "B.SilkS")
		)
		(fp_poly
			(pts
				(xy 0.5334 0.254) (xy 0.635 0.254) (xy 0.635 0.2286) (xy 0.635 -0.254) (xy 0.5334 -0.254) (xy 0.5334 -0.2794)
				(xy -0.5334 -0.2794) (xy -0.5334 -0.254) (xy -0.635 -0.254) (xy -0.635 0.254) (xy -0.5334 0.254)
				(xy -0.5334 0.2794) (xy 0.508 0.2794) (xy 0.5334 0.2794)
			)
			(stroke
				(width 0)
				(type default)
			)
			(fill no)
			(layer "B.CrtYd")
		)
		(pad "1" smd rect
			(at -0.40005 0 270)
			(size 0.4572 0.508)
			(layers "B.Cu" "B.Mask" "B.Paste")
			(net "P3V3_NODE1")
		)
		(pad "2" smd rect
			(at 0.40005 0 270)
			(size 0.4572 0.508)
			(layers "B.Cu" "B.Mask" "B.Paste")
			(net "GND")
		)
	)
	(footprint ""
		(layer "B.Cu")
		(at 23.847298 -108.443522)
		(property "Reference" "C55"
			(at -3.015996 -0.770382 0)
			(unlocked yes)
			(layer "B.SilkS")
			(effects
				(font
					(size 0.7874 0.5842)
					(thickness 0.1524)
				)
				(justify left mirror)
			)
		)
		(property "Value" ""
			(at 0 0 0)
			(layer "B.Fab")
			(effects
				(font
					(size 1.27 1.27)
				)
				(justify mirror)
			)
		)
		(duplicate_pad_numbers_are_jumpers no)
		(fp_line
			(start -1.905 -0.8636)
			(end -1.905 0.8636)
			(stroke
				(width 0.1524)
				(type default)
			)
			(layer "B.SilkS")
		)
		(fp_line
			(start -1.905 0.8636)
			(end 1.905 0.8636)
			(stroke
				(width 0.1524)
				(type default)
			)
			(layer "B.SilkS")
		)
		(fp_line
			(start 0 0.8382)
			(end 0 -0.8382)
			(stroke
				(width 0.1524)
				(type default)
			)
			(layer "B.SilkS")
		)
		(fp_line
			(start 1.905 -0.8636)
			(end -1.905 -0.8636)
			(stroke
				(width 0.1524)
				(type default)
			)
			(layer "B.SilkS")
		)
		(fp_line
			(start 1.905 0.8636)
			(end 1.905 -0.8636)
			(stroke
				(width 0.1524)
				(type default)
			)
			(layer "B.SilkS")
		)
		(fp_rect
			(start 1.524 0.7366)
			(end -1.524 -0.7366)
			(stroke
				(width 0)
				(type default)
			)
			(fill no)
			(layer "B.CrtYd")
		)
		(pad "1" smd rect
			(at -0.94996 0 180)
			(size 1.1176 1.3716)
			(layers "B.Cu" "B.Mask" "B.Paste")
			(net "P1V05_NODE1")
		)
		(pad "2" smd rect
			(at 0.94996 0 180)
			(size 1.1176 1.3716)
			(layers "B.Cu" "B.Mask" "B.Paste")
			(net "GND")
		)
	)
	(footprint ""
		(layer "B.Cu")
		(at 164.10178 -157.795722 -90)
		(property "Reference" "C441"
			(at -2.140966 0.300228 270)
			(unlocked yes)
			(layer "B.SilkS")
			(effects
				(font
					(size 0.7874 0.5842)
					(thickness 0.1524)
				)
				(justify left mirror)
			)
		)
		(property "Value" ""
			(at 0 0 90)
			(layer "B.Fab")
			(effects
				(font
					(size 1.27 1.27)
				)
				(justify mirror)
			)
		)
		(duplicate_pad_numbers_are_jumpers no)
		(fp_line
			(start -0.7874 0.4064)
			(end 0.7874 0.4064)
			(stroke
				(width 0.1524)
				(type default)
			)
			(layer "B.SilkS")
		)
		(fp_line
			(start 0.7874 0.4064)
			(end 0.7874 -0.4064)
			(stroke
				(width 0.1524)
				(type default)
			)
			(layer "B.SilkS")
		)
		(fp_line
			(start 0 0.381)
			(end 0 -0.381)
			(stroke
				(width 0.1524)
				(type default)
			)
			(layer "B.SilkS")
		)
		(fp_line
			(start -0.7874 -0.4064)
			(end -0.7874 0.4064)
			(stroke
				(width 0.1524)
				(type default)
			)
			(layer "B.SilkS")
		)
		(fp_line
			(start 0.7874 -0.4064)
			(end -0.7874 -0.4064)
			(stroke
				(width 0.1524)
				(type default)
			)
			(layer "B.SilkS")
		)
		(fp_poly
			(pts
				(xy 0.5334 0.254) (xy 0.635 0.254) (xy 0.635 0.2286) (xy 0.635 -0.254) (xy 0.5334 -0.254) (xy 0.5334 -0.2794)
				(xy -0.5334 -0.2794) (xy -0.5334 -0.254) (xy -0.635 -0.254) (xy -0.635 0.254) (xy -0.5334 0.254)
				(xy -0.5334 0.2794) (xy 0.508 0.2794) (xy 0.5334 0.2794)
			)
			(stroke
				(width 0)
				(type default)
			)
			(fill no)
			(layer "B.CrtYd")
		)
		(pad "1" smd rect
			(at -0.40005 0 90)
			(size 0.4572 0.508)
			(layers "B.Cu" "B.Mask" "B.Paste")
			(net "P3V3_NODE1")
		)
		(pad "2" smd rect
			(at 0.40005 0 90)
			(size 0.4572 0.508)
			(layers "B.Cu" "B.Mask" "B.Paste")
			(net "GND")
		)
	)
	(footprint ""
		(layer "B.Cu")
		(at 110.85576 -185.205624 -90)
		(property "Reference" "C730"
			(at -3.957828 -0.466598 270)
			(unlocked yes)
			(layer "B.SilkS")
			(effects
				(font
					(size 0.7874 0.5842)
					(thickness 0.1524)
				)
				(justify left mirror)
			)
		)
		(property "Value" ""
			(at 0 0 90)
			(layer "B.Fab")
			(effects
				(font
					(size 1.27 1.27)
				)
				(justify mirror)
			)
		)
		(duplicate_pad_numbers_are_jumpers no)
		(fp_line
			(start -0.7874 0.4064)
			(end 0.7874 0.4064)
			(stroke
				(width 0.1524)
				(type default)
			)
			(layer "B.SilkS")
		)
		(fp_line
			(start 0.7874 0.4064)
			(end 0.7874 -0.4064)
			(stroke
				(width 0.1524)
				(type default)
			)
			(layer "B.SilkS")
		)
		(fp_line
			(start 0 0.381)
			(end 0 -0.381)
			(stroke
				(width 0.1524)
				(type default)
			)
			(layer "B.SilkS")
		)
		(fp_line
			(start -0.7874 -0.4064)
			(end -0.7874 0.4064)
			(stroke
				(width 0.1524)
				(type default)
			)
			(layer "B.SilkS")
		)
		(fp_line
			(start 0.7874 -0.4064)
			(end -0.7874 -0.4064)
			(stroke
				(width 0.1524)
				(type default)
			)
			(layer "B.SilkS")
		)
		(fp_poly
			(pts
				(xy 0.5334 0.254) (xy 0.635 0.254) (xy 0.635 0.2286) (xy 0.635 -0.254) (xy 0.5334 -0.254) (xy 0.5334 -0.2794)
				(xy -0.5334 -0.2794) (xy -0.5334 -0.254) (xy -0.635 -0.254) (xy -0.635 0.254) (xy -0.5334 0.254)
				(xy -0.5334 0.2794) (xy 0.508 0.2794) (xy 0.5334 0.2794)
			)
			(stroke
				(width 0)
				(type default)
			)
			(fill no)
			(layer "B.CrtYd")
		)
		(pad "1" smd rect
			(at -0.40005 0 90)
			(size 0.4572 0.508)
			(layers "B.Cu" "B.Mask" "B.Paste")
			(net "UART_T7_NODE3_RXD")
		)
		(pad "2" smd rect
			(at 0.40005 0 90)
			(size 0.4572 0.508)
			(layers "B.Cu" "B.Mask" "B.Paste")
			(net "GND")
		)
	)
	(footprint ""
		(layer "B.Cu")
		(at 142.470632 -163.353242 180)
		(property "Reference" "R1001"
			(at -0.293116 -4.485386 270)
			(unlocked yes)
			(layer "B.SilkS")
			(effects
				(font
					(size 0.7874 0.5842)
					(thickness 0.1524)
				)
				(justify left mirror)
			)
		)
		(property "Value" ""
			(at 0 0 0)
			(layer "B.Fab")
			(effects
				(font
					(size 1.27 1.27)
				)
				(justify mirror)
			)
		)
		(duplicate_pad_numbers_are_jumpers no)
		(fp_line
			(start 0.7874 0.4064)
			(end 0.7874 -0.4064)
			(stroke
				(width 0.1524)
				(type default)
			)
			(layer "B.SilkS")
		)
		(fp_line
			(start 0.7874 -0.4064)
			(end -0.7874 -0.4064)
			(stroke
				(width 0.1524)
				(type default)
			)
			(layer "B.SilkS")
		)
		(fp_line
			(start -0.7874 0.4064)
			(end 0.7874 0.4064)
			(stroke
				(width 0.1524)
				(type default)
			)
			(layer "B.SilkS")
		)
		(fp_line
			(start -0.7874 -0.4064)
			(end -0.7874 0.4064)
			(stroke
				(width 0.1524)
				(type default)
			)
			(layer "B.SilkS")
		)
		(fp_poly
			(pts
				(xy 0.508 0.2794) (xy 0.508 0.2286) (xy 0.635 0.2286) (xy 0.635 -0.254) (xy 0.5334 -0.254) (xy 0.5334 -0.2794)
				(xy -0.5334 -0.2794) (xy -0.5334 -0.254) (xy -0.635 -0.254) (xy -0.635 0.254) (xy -0.5334 0.254)
				(xy -0.5334 0.2794)
			)
			(stroke
				(width 0)
				(type default)
			)
			(fill no)
			(layer "B.CrtYd")
		)
		(pad "1" smd rect
			(at -0.40005 0)
			(size 0.4572 0.508)
			(layers "B.Cu" "B.Mask" "B.Paste")
			(net "UART_T10_NODE4_TXD")
		)
		(pad "2" smd rect
			(at 0.40005 0)
			(size 0.4572 0.508)
			(layers "B.Cu" "B.Mask" "B.Paste")
			(net "UART_T10_NODE4_TXD_R")
		)
	)
	(footprint ""
		(layer "B.Cu")
		(at 91.102434 -184.794398 180)
		(property "Reference" "R924"
			(at 2.352294 4.044442 0)
			(unlocked yes)
			(layer "B.SilkS")
			(effects
				(font
					(size 0.7874 0.5842)
					(thickness 0.1524)
				)
				(justify left mirror)
			)
		)
		(property "Value" ""
			(at 0 0 0)
			(layer "B.Fab")
			(effects
				(font
					(size 1.27 1.27)
				)
				(justify mirror)
			)
		)
		(duplicate_pad_numbers_are_jumpers no)
		(fp_line
			(start 0.7874 0.4064)
			(end 0.7874 -0.4064)
			(stroke
				(width 0.1524)
				(type default)
			)
			(layer "B.SilkS")
		)
		(fp_line
			(start 0.7874 -0.4064)
			(end -0.7874 -0.4064)
			(stroke
				(width 0.1524)
				(type default)
			)
			(layer "B.SilkS")
		)
		(fp_line
			(start -0.7874 0.4064)
			(end 0.7874 0.4064)
			(stroke
				(width 0.1524)
				(type default)
			)
			(layer "B.SilkS")
		)
		(fp_line
			(start -0.7874 -0.4064)
			(end -0.7874 0.4064)
			(stroke
				(width 0.1524)
				(type default)
			)
			(layer "B.SilkS")
		)
		(fp_poly
			(pts
				(xy 0.508 0.2794) (xy 0.508 0.2286) (xy 0.635 0.2286) (xy 0.635 -0.254) (xy 0.5334 -0.254) (xy 0.5334 -0.2794)
				(xy -0.5334 -0.2794) (xy -0.5334 -0.254) (xy -0.635 -0.254) (xy -0.635 0.254) (xy -0.5334 0.254)
				(xy -0.5334 0.2794)
			)
			(stroke
				(width 0)
				(type default)
			)
			(fill no)
			(layer "B.CrtYd")
		)
		(pad "1" smd rect
			(at -0.40005 0)
			(size 0.4572 0.508)
			(layers "B.Cu" "B.Mask" "B.Paste")
			(net "UART_T5_NODE3_TXD")
		)
		(pad "2" smd rect
			(at 0.40005 0)
			(size 0.4572 0.508)
			(layers "B.Cu" "B.Mask" "B.Paste")
			(net "UART_T5_NODE3_TXD_R")
		)
	)
)
